FILE_TYPE = CONNECTIVITY;
{Allegro Design Entry HDL 17.2-2016 S081 (4005846) 1/11/2022}
"PAGE_NUMBER" = 217;
0"NC";
1"P3V3_AUX\g";
2"PVNN_TERM_CPU0\g";
3"P3V3_AUX\g";
4"GND\g";
5"GND\g";
6"GND\g";
7"GND\g";
8"FM_SPD_REMOTE_EN_R"CDS_PHYS_NET_NAME"FM_SPD_REMOTE_EN_R";
9"FM_SPD_REMOTE_EN";
10"PD_I3C_SPD_DDR_CPU0_OE_N";
11"I3C_SPD_DDREFGH_CPU0_R_SDA";
12"I3C_SPD_DDREFGH_CPU0_BMC_SDA";
13"I3C_SPD_DDRABCD_CPU0_R_SCL";
14"I3C_SPD_DDRABCD_CPU0_LVC1_SCL";
15"I3C_SPD_DDRABCD_CPU0_LVC1_SDA";
16"I3C_SPD_DDREFGH_CPU0_LVC1_SCL";
17"I3C_SPD_DDREFGH_CPU0_LVC1_SDA";
18"FM_SPD_REMOTE_EN"CDS_PHYS_NET_NAME"FM_SPD_REMOTE_EN";
19"I3C_SPD_DDREFGH_CPU0_R_SDA";
20"I3C_SPD_DDRABCD_CPU0_R_SDA";
21"I3C_SPD_DDREFGH_CPU0_R_SCL";
22"I3C_SPD_DDRABCD_CPU0_SDA";
23"I3C_SPD_DDRABCD_CPU0_SCL";
24"I3C_SPD_DDRABCD_CPU0_LVC1_R_SCL";
25"I3C_SPD_DDRABCD_CPU0_LVC1_R_SDA";
26"I3C_SPD_DDREFGH_CPU0_LVC1_R_SCL";
27"I3C_SPD_DDREFGH_CPU0_LVC1_R_SDA";
28"I3C_SPD_DDRABCD_CPU0_R_SCL";
29"I3C_SPD_DDRABCD_CPU0_R_SDA";
30"I3C_SPD_DDREFGH_CPU0_R_SCL";
31"I3C_SPD_DDRABCD_CPU0_BMC_SCL";
32"I3C_SPD_DDRABCD_CPU0_BMC_SDA";
33"I3C_SPD_DDREFGH_CPU0_SDA";
34"I3C_SPD_DDREFGH_CPU0_SCL";
35"I3C_SPD_DDREFGH_CPU0_BMC_SCL";
%"UNIVERSAL_GND"
"1","(-3050,900)","0","logical_power","I12";
;
HDL_POWER"GND"
CDS_LIB"logical_power";
"A"4;
%"Q_RES"
"2","(-3050,1125)","0","pure_quanta","I13";
;
PART_NUMBER"CS21002FB06"
PACK_TYPE"0402LF"
MATERIAL"CHIP"
WATTAGE"1/16W"
TOLERANCE"1%"
VALUE"1K"
$LOCATION"R678"
CDS_LIB"pure_quanta"
CDS_LOCATION"R678"
$SEC"1"
CDS_SEC"1";
"A"
$PN"1"10;
"B"
$PN"2"4;
%"Q_RES"
"1","(-1375,675)","0","pure_quanta","I16";
;
PART_NUMBER"CS00002JB13"
MATERIAL"EMPTY"
PACK_TYPE"0402LF"
TOLERANCE"5%"
VALUE"0"
WATTAGE"1/16W"
$LOCATION"R685"
CDS_LIB"pure_quanta"
CDS_LOCATION"R685"
$SEC"1"
CDS_SEC"1";
"B"
$PN"2"27;
"A"
$PN"1"11;
%"Q_RES"
"1","(-1375,800)","0","pure_quanta","I17";
;
PART_NUMBER"CS00002JB13"
PACK_TYPE"0402LF"
MATERIAL"EMPTY"
TOLERANCE"5%"
VALUE"0"
WATTAGE"1/16W"
$LOCATION"R684"
CDS_LIB"pure_quanta"
CDS_LOCATION"R684"
$SEC"1"
CDS_SEC"1";
"B"
$PN"2"26;
"A"
$PN"1"30;
%"Q_RES"
"1","(-1375,925)","0","pure_quanta","I18";
;
PART_NUMBER"CS00002JB13"
MATERIAL"EMPTY"
VALUE"0"
TOLERANCE"5%"
PACK_TYPE"0402LF"
WATTAGE"1/16W"
$LOCATION"R683"
CDS_LIB"pure_quanta"
CDS_LOCATION"R683"
$SEC"1"
CDS_SEC"1";
"B"
$PN"2"25;
"A"
$PN"1"29;
%"QS3VH257QG8"
"1","(-1350,1650)","2","pure_quanta","I19";
;
PART_NUMBER"AL000257W24"
PACK_TYPE"SMLF"
VALUE"QS3VH257QG8"
MATERIAL"IC"
LOCATION"U15"
NEEDS_NO_SIZE"TRUE"
CDS_LIB"pure_quanta"
CDS_LMAN_SYM_OUTLINE"-150,375,150,-375"
$SEC"1"
CDS_SEC"1";
"I1D"
$PN"13"12;
"I0D"
$PN"14"11;
"YD"
$PN"12"27;
"YC"
$PN"9"26;
"I1C"
$PN"10"35;
"I0C"
$PN"11"30;
"YB"
$PN"7"25;
"I1B"
$PN"6"32;
"I0B"
$PN"5"29;
"I1A"
$PN"3"31;
"I0A"
$PN"2"28;
"VCC"
$PN"16"1;
"GND"
$PN"8"5;
"YA"
$PN"4"24;
"E*"
$PN"15"10;
"S"
$PN"1"9;
%"Q_RES"
"1","(-1375,1050)","0","pure_quanta","I20";
;
PART_NUMBER"CS00002JB13"
VALUE"0"
TOLERANCE"5%"
PACK_TYPE"0402LF"
WATTAGE"1/16W"
MATERIAL"EMPTY"
$LOCATION"R682"
CDS_LIB"pure_quanta"
CDS_LOCATION"R682"
$SEC"1"
CDS_SEC"1";
"B"
$PN"2"24;
"A"
$PN"1"28;
%"UNIVERSAL_GND"
"1","(-975,1200)","0","logical_power","I21";
;
HDL_POWER"GND"
CDS_LIB"logical_power";
"A"5;
%"UNIVERSAL_GND"
"1","(-750,2000)","0","logical_power","I22";
;
HDL_POWER"GND"
CDS_LIB"logical_power";
"A"6;
%"UNIVERSAL_POWER"
"1","(-975,2575)","0","logical_power","I23";
;
HDL_POWER"P3V3_AUX"
CDS_LIB"logical_power";
"A"1;
%"Q_CAP"
"1","(-750,2250)","0","pure_quanta","I24";
;
PART_NUMBER"CH4104K1B00"
VOLTAGE"25V"
PACK_TYPE"0402"
TOLERANCE"10%"
VALUE"0.1UF"
MATERIAL"X7R"
$LOCATION"C538"
CDS_LIB"pure_quanta"
CDS_LOCATION"C538"
$SEC"1"
CDS_SEC"1";
"B"
$PN"2"6;
"A"
$PN"1"1;
%"Q_RES"
"1","(-875,3975)","0","pure_quanta","I25";
;
PART_NUMBER"CS00002JB13"
TOLERANCE"5%"
MATERIAL"CHIP"
WATTAGE"1/16W"
PACK_TYPE"0402LF"
VALUE"0"
LOCATION"R689"
CDS_LIB"pure_quanta"
$SEC"1"
CDS_SEC"1";
"B"
$PN"2"21;
"A"
$PN"1"34;
%"Q_RES"
"1","(-875,3925)","0","pure_quanta","I26";
;
PART_NUMBER"CS03322FB03"
VALUE"33.2"
TOLERANCE"1%"
PACK_TYPE"0402LF"
$LOCATION"R690"
MATERIAL"CHIP"
WATTAGE"1/16W"
CDS_LIB"pure_quanta"
CDS_LOCATION"R690"
$SEC"1"
CDS_SEC"1";
"B"
$PN"2"19;
"A"
$PN"1"33;
%"Q_RES"
"2","(-1975,4600)","0","pure_quanta","I29";
;
PART_NUMBER"CS14992FB06"
WATTAGE"1/16W"
VALUE"499"
TOLERANCE"1%"
MATERIAL"CHIP"
PACK_TYPE"0402LF"
$LOCATION"R679"
CDS_LIB"pure_quanta"
CDS_LOCATION"R679"
$SEC"1"
CDS_SEC"1";
"A"
$PN"1"2;
"B"
$PN"2"23;
%"Q_RES"
"2","(-1725,4600)","0","pure_quanta","I30";
;
PART_NUMBER"CS14992FB06"
WATTAGE"1/16W"
TOLERANCE"1%"
MATERIAL"CHIP"
PACK_TYPE"0402LF"
VALUE"499"
$LOCATION"R680"
CDS_LIB"pure_quanta"
CDS_LOCATION"R680"
$SEC"1"
CDS_SEC"1";
"A"
$PN"1"2;
"B"
$PN"2"22;
%"UNIVERSAL_POWER"
"1","(-1975,4975)","0","logical_power","I31";
;
HDL_POWER"PVNN_TERM_CPU0"
CDS_LIB"logical_power";
"A"2;
%"Q_RES"
"2","(-1475,4600)","0","pure_quanta","I32";
;
PART_NUMBER"CS14992FB06"
MATERIAL"CHIP"
WATTAGE"1/16W"
PACK_TYPE"0402LF"
VALUE"499"
TOLERANCE"1%"
$LOCATION"R681"
CDS_LIB"pure_quanta"
CDS_LOCATION"R681"
$SEC"1"
CDS_SEC"1";
"A"
$PN"1"2;
"B"
$PN"2"34;
%"Q_RES"
"2","(-1225,4600)","0","pure_quanta","I33";
;
PART_NUMBER"CS14992FB06"
PACK_TYPE"0402LF"
VALUE"499"
MATERIAL"CHIP"
TOLERANCE"1%"
WATTAGE"1/16W"
$LOCATION"R686"
CDS_LIB"pure_quanta"
CDS_LOCATION"R686"
$SEC"1"
CDS_SEC"1";
"A"
$PN"1"2;
"B"
$PN"2"33;
%"Q_RES"
"1","(-875,4275)","0","pure_quanta","I34";
;
PART_NUMBER"CS00002JB13"
TOLERANCE"5%"
MATERIAL"CHIP"
WATTAGE"1/16W"
PACK_TYPE"0402LF"
VALUE"0"
LOCATION"R687"
CDS_LIB"pure_quanta"
$SEC"1"
CDS_SEC"1";
"B"
$PN"2"13;
"A"
$PN"1"23;
%"Q_RES"
"1","(-875,4225)","0","pure_quanta","I35";
;
PART_NUMBER"CS03322FB03"
PACK_TYPE"0402LF"
VALUE"33.2"
TOLERANCE"1%"
$LOCATION"R688"
MATERIAL"CHIP"
WATTAGE"1/16W"
CDS_LIB"pure_quanta"
CDS_LOCATION"R688"
$SEC"1"
CDS_SEC"1";
"B"
$PN"2"20;
"A"
$PN"1"22;
%"Q_RES"
"1","(750,1475)","0","pure_quanta","I37";
;
PART_NUMBER"CS03322FB03"
VALUE"33.2"
TOLERANCE"1%"
$LOCATION"R694"
PACK_TYPE"0402LF"
MATERIAL"CHIP"
WATTAGE"1/16W"
CDS_LIB"pure_quanta"
CDS_LOCATION"R694"
$SEC"1"
CDS_SEC"1";
"B"
$PN"2"17;
"A"
$PN"1"27;
%"Q_RES"
"1","(750,1625)","0","pure_quanta","I38";
;
PART_NUMBER"CS00002JB13"
VALUE"0"
TOLERANCE"5%"
$LOCATION"R693"
MATERIAL"CHIP"
WATTAGE"1/16W"
CDS_LIB"pure_quanta"
PACK_TYPE"0402LF"
CDS_LOCATION"R693"
$SEC"1"
CDS_SEC"1";
"B"
$PN"2"16;
"A"
$PN"1"26;
%"Q_RES"
"1","(750,1925)","0","pure_quanta","I39";
;
PART_NUMBER"CS00002JB13"
TOLERANCE"5%"
MATERIAL"CHIP"
WATTAGE"1/16W"
VALUE"0"
PACK_TYPE"0402LF"
$LOCATION"R691"
CDS_LIB"pure_quanta"
CDS_LOCATION"R691"
$SEC"1"
CDS_SEC"1";
"B"
$PN"2"14;
"A"
$PN"1"24;
%"Q_RES"
"1","(750,1775)","0","pure_quanta","I40";
;
PART_NUMBER"CS03322FB03"
TOLERANCE"1%"
VALUE"33.2"
$LOCATION"R692"
PACK_TYPE"0402LF"
CDS_LIB"pure_quanta"
WATTAGE"1/16W"
MATERIAL"CHIP"
CDS_LOCATION"R692"
$SEC"1"
CDS_SEC"1";
"B"
$PN"2"15;
"A"
$PN"1"25;
%"UNIVERSAL_GND"
"1","(1600,300)","0","logical_power","I41";
;
HDL_POWER"GND"
ROOM"IO_SLOT"
CDS_LIB"logical_power";
"A"7;
%"Q_RES"
"2","(1600,525)","0","pure_quanta","I42";
;
PART_NUMBER"CS31002FB08"
VALUE"10K"
TOLERANCE"1%"
MATERIAL"CHIP"
PACK_TYPE"0402LF"
WATTAGE"1/16W"
$LOCATION"R318"
CDS_LIB"pure_quanta"
$LOCATION"R318"
CDS_LOCATION"R318"
$SEC"1"
CDS_SEC"1";
"A"
$PN"1"18;
"B"
$PN"2"7;
%"Q_RES"
"2","(1600,950)","0","pure_quanta","I43";
;
PART_NUMBER"CS21002FB06"
TOLERANCE"1%"
WATTAGE"1/16W"
MATERIAL"EMPTY"
VALUE"1K"
PACK_TYPE"0402LF"
$LOCATION"R87"
CDS_LIB"pure_quanta"
$LOCATION"R87"
CDS_LOCATION"R87"
$SEC"1"
CDS_SEC"1";
"A"
$PN"1"3;
"B"
$PN"2"18;
%"UNIVERSAL_POWER"
"1","(1600,1200)","0","logical_power","I44";
;
HDL_POWER"P3V3_AUX"
CDS_LIB"logical_power";
"A"3;
%"Q_RES"
"1","(-3700,1200)","0","pure_quanta","I53";
;
PART_NUMBER"CS12002FB06"
VALUE"200"
PACK_TYPE"0402LF"
MATERIAL"CHIP"
WATTAGE"1/16W"
TOLERANCE"1%"
$LOCATION"R1821"
CDS_LIB"pure_quanta"
CDS_LOCATION"R1821"
$SEC"1"
CDS_SEC"1";
"B"
$PN"2"9;
"A"
$PN"1"8;
END.
